FILE_TYPE = CONNECTIVITY;
{Allegro Design Entry HDL 16.6-p007 (v16-6-112F) 10/10/2012}
"PAGE_NUMBER" = 42;
0"NC";
1"PVCCIN_CPU0\g";
2"GND\g";
3"GND\g";
4"GND\g";
5"PVCCIN_CPU0\g";
6"PVCCIN_CPU0\g";
7"PVCCIN_CPU0\g";
8"GND\g";
9"GND\g";
10"GND\g";
11"PVCCIN_CPU0\g";
12"PVCCIN_CPU0\g";
13"PVCCMCP_CPU0\g";
14"PVCCMCP_CPU0\g";
15"PVCCIO_CPU0\g";
16"PVCCMCP_CPU0\g";
17"PVCCIN_CPU0\g";
18"GND\g";
19"PVCCIN_CPU0\g";
20"GND\g";
21"PVCCIN_CPU0\g";
22"GND\g";
23"GND\g";
24"GND\g";
25"PVCCIN_CPU0\g";
26"PVCCMCP_CPU0\g";
27"GND\g";
28"GND\g";
29"PVSA_CPU0\g";
30"GND\g";
31"GND\g";
32"PVCCIN_CPU0\g";
33"PVCCIN_CPU0\g";
34"GND\g";
35"GND\g";
36"GND\g";
37"GND\g";
38"PVCCIN_CPU0\g";
39"PVCCIN_CPU0\g";
40"GND\g";
41"GND\g";
42"PVCCIO_CPU0\g";
43"GND\g";
44"PVSA_CPU0\g";
%"CAP"
"1","(-2550,950)","0","mstr_discrete","I10";
;
VOLTAGE"4V"
PART_NUMBER"C95333-006"
GROUP"PWR_MLCC_CAP"
PACK_TYPE"0805"
MATERIAL"X6S"
TOLERANCE"20%"
VALUE"47UF"
LOCATION"C4P1"
BOM_COST"PROC_SOCKET"
CDS_LIB"mstr_discrete"
CDS_SEC"1"
$SEC"1"
CDS_LOCATION"C4P1"
ROOM"PVCCIN_CPU0_DECAP_VR";
"A"
$PN"1"15;
"B"
$PN"2"18;
%"CAP_A"
"1","(-4900,3800)","0","dev_discrete","I100";
;
VALUE"22.0UF"
VOLTAGE"4V"
TOLERANCE"20%"
LOCATION"C5D28"
MATERIAL"X6S"
PART_NUMBER"E15431-004"
PACK_TYPE"0603V"
GROUP"PWR_MLCC_CAP"
CDS_LOCATION"C5D28"
BOM_COST"PROC_SOCKET"
CDS_LIB"dev_discrete"
CDS_SEC"1"
$SEC"1"
ROOM"PVCCIN_CPU0_DECAP_VR";
"B"
$PN"2"2;
"A"
$PN"1"6;
%"GND"
"1","(-5950,3525)","0","mstr_symbols","I101";
;
HDL_POWER"GND"
BODY_TYPE"PLUMBING"
SIZE"1B"
CDS_LIB"mstr_symbols"
VOLTAGE"0";
"A\NAC"2;
%"CAP_A"
"1","(-4750,4500)","0","dev_discrete","I102";
;
GROUP"PWR_MLCC_CAP"
VALUE"22.0UF"
PACK_TYPE"0603V"
TOLERANCE"20%"
VOLTAGE"4V"
LOCATION"C5D29"
MATERIAL"X6S"
PART_NUMBER"E15431-004"
CDS_LOCATION"C5D29"
BOM_COST"PROC_SOCKET"
CDS_LIB"dev_discrete"
CDS_SEC"1"
$SEC"1"
ROOM"PVCCIN_CPU0_DECAP_VR";
"B"
$PN"2"3;
"A"
$PN"1"5;
%"CAP_A"
"1","(-5050,4500)","0","dev_discrete","I103";
;
VALUE"22.0UF"
GROUP"PWR_MLCC_CAP"
LOCATION"C5D32"
VOLTAGE"4V"
TOLERANCE"20%"
PACK_TYPE"0603V"
MATERIAL"X6S"
PART_NUMBER"E15431-004"
ROOM"PVCCIN_CPU0_DECAP_VR"
$SEC"1"
CDS_SEC"1"
CDS_LIB"dev_discrete"
BOM_COST"PROC_SOCKET"
CDS_LOCATION"C5D32";
"B"
$PN"2"3;
"A"
$PN"1"5;
%"CAP_A"
"1","(-5350,4500)","0","dev_discrete","I104";
;
VALUE"22.0UF"
GROUP"PWR_MLCC_CAP"
MATERIAL"X6S"
VOLTAGE"4V"
TOLERANCE"20%"
PACK_TYPE"0603V"
PART_NUMBER"E15431-004"
LOCATION"C5D47"
ROOM"PVCCIN_CPU0_DECAP_VR"
$SEC"1"
CDS_SEC"1"
CDS_LIB"dev_discrete"
BOM_COST"PROC_SOCKET"
CDS_LOCATION"C5D47";
"B"
$PN"2"3;
"A"
$PN"1"5;
%"GND"
"1","(-5950,4225)","0","mstr_symbols","I105";
;
VOLTAGE"0"
SIZE"1B"
CDS_LIB"mstr_symbols"
BODY_TYPE"PLUMBING"
HDL_POWER"GND";
"A\NAC"3;
%"CAP_A"
"1","(-5200,3800)","0","dev_discrete","I106";
;
TOLERANCE"20%"
MATERIAL"X6S"
LOCATION"C5D31"
VALUE"22.0UF"
VOLTAGE"4V"
GROUP"PWR_MLCC_CAP"
PACK_TYPE"0603V"
PART_NUMBER"E15431-004"
CDS_LOCATION"C5D31"
BOM_COST"PROC_SOCKET"
CDS_LIB"dev_discrete"
CDS_SEC"1"
$SEC"1"
ROOM"PVCCIN_CPU0_DECAP_VR";
"B"
$PN"2"2;
"A"
$PN"1"6;
%"CAP_A"
"1","(-5500,3800)","0","dev_discrete","I107";
;
LOCATION"C5D46"
VALUE"22.0UF"
VOLTAGE"4V"
TOLERANCE"20%"
MATERIAL"X6S"
PART_NUMBER"E15431-004"
PACK_TYPE"0603V"
GROUP"PWR_MLCC_CAP"
ROOM"PVCCIN_CPU0_DECAP_VR"
$SEC"1"
CDS_SEC"1"
CDS_LIB"dev_discrete"
BOM_COST"PROC_SOCKET"
CDS_LOCATION"C5D46";
"B"
$PN"2"2;
"A"
$PN"1"6;
%"CAP"
"1","(-4100,3150)","0","mstr_discrete","I108";
;
PART_NUMBER"E15431-001"
MATERIAL"X6S"
PACK_TYPE"0603LF"
GROUP"PWR_MLCC_CAP"
TOLERANCE"20%"
VALUE"10UF"
VOLTAGE"4V"
LOCATION"C5D10"
ROOM"PVCCIN_CPU0_DECAP_VR"
CDS_LOCATION"C5D10"
$SEC"1"
CDS_SEC"1"
CDS_LIB"mstr_discrete"
BOM_COST"PROC_SOCKET";
"A"
$PN"1"44;
"B"
$PN"2"43;
%"CAP_A"
"1","(-5000,3150)","0","dev_discrete","I109";
;
LOCATION"C5D27"
MATERIAL"X6S"
PART_NUMBER"E15431-004"
VALUE"22.0UF"
VOLTAGE"4V"
TOLERANCE"20%"
PACK_TYPE"0603V"
GROUP"PWR_MLCC_CAP"
ROOM"PVCCIN_CPU0_DECAP_VR"
$SEC"1"
CDS_SEC"1"
CDS_LIB"dev_discrete"
BOM_COST"PROC_SOCKET"
CDS_LOCATION"C5D27";
"B"
$PN"2"4;
"A"
$PN"1"7;
%"GND"
"1","(-5950,2875)","0","mstr_symbols","I110";
;
VOLTAGE"0"
SIZE"1B"
CDS_LIB"mstr_symbols"
BODY_TYPE"PLUMBING"
HDL_POWER"GND";
"A\NAC"4;
%"CAP_A"
"1","(-5300,3150)","0","dev_discrete","I111";
;
PACK_TYPE"0603V"
MATERIAL"X6S"
TOLERANCE"20%"
VOLTAGE"4V"
VALUE"22.0UF"
PART_NUMBER"E15431-004"
GROUP"PWR_MLCC_CAP"
LOCATION"C5D30"
CDS_LOCATION"C5D30"
BOM_COST"PROC_SOCKET"
CDS_LIB"dev_discrete"
CDS_SEC"1"
$SEC"1"
ROOM"PVCCIN_CPU0_DECAP_VR";
"B"
$PN"2"4;
"A"
$PN"1"7;
%"CAP_A"
"1","(-5800,3800)","0","dev_discrete","I114";
;
LOCATION"C5D41"
VALUE"22.0UF"
VOLTAGE"4V"
TOLERANCE"20%"
PACK_TYPE"0603V"
MATERIAL"X6S"
PART_NUMBER"E15431-004"
GROUP"PWR_MLCC_CAP"
CDS_LOCATION"C5D41"
BOM_COST"PROC_SOCKET"
CDS_LIB"dev_discrete"
CDS_SEC"1"
$SEC"1"
ROOM"PVCCIN_CPU0_DECAP_VR";
"B"
$PN"2"2;
"A"
$PN"1"6;
%"CAP_A"
"1","(-5650,4500)","0","dev_discrete","I115";
;
MATERIAL"X6S"
PART_NUMBER"E15431-004"
PACK_TYPE"0603V"
VOLTAGE"4V"
TOLERANCE"20%"
VALUE"22.0UF"
LOCATION"C5D40"
GROUP"PWR_MLCC_CAP"
ROOM"PVCCIN_CPU0_DECAP_VR"
$SEC"1"
CDS_SEC"1"
CDS_LIB"dev_discrete"
BOM_COST"PROC_SOCKET"
CDS_LOCATION"C5D40";
"B"
$PN"2"3;
"A"
$PN"1"5;
%"PVCCIN_CPU0"
"1","(-5950,4800)","0","mstr_symbols","I116";
;
HDL_POWER"PVCCIN_CPU0"
BODY_TYPE"PLUMBING"
CDS_LIB"mstr_symbols"
VOLTAGE"2.0V";
"G\NAC"5;
%"CAP_A"
"1","(-5950,4500)","0","dev_discrete","I117";
;
LOCATION"C5D14"
VALUE"22.0UF"
VOLTAGE"4V"
TOLERANCE"20%"
MATERIAL"X6S"
PART_NUMBER"E15431-004"
PACK_TYPE"0603V"
GROUP"PWR_MLCC_CAP"
ROOM"PVCCIN_CPU0_DECAP_VR"
$SEC"1"
CDS_SEC"1"
CDS_LIB"dev_discrete"
BOM_COST"PROC_SOCKET"
CDS_LOCATION"C5D14";
"B"
$PN"2"3;
"A"
$PN"1"5;
%"CAP_A"
"1","(-6750,4500)","0","dev_discrete","I118";
;
TOLERANCE"20%"
MATERIAL"X6S"
VOLTAGE"4V"
LOCATION"C5D17"
VALUE"22.0UF"
PART_NUMBER"E15431-004"
PACK_TYPE"0603V"
GROUP"PWR_MLCC_CAP"
ROOM"PVCCIN_CPU0_DECAP_VR"
$SEC"1"
CDS_SEC"1"
CDS_LIB"dev_discrete"
BOM_COST"PROC_SOCKET"
CDS_LOCATION"C5D17";
"B"
$PN"2"8;
"A"
$PN"1"11;
%"PVCCIN_CPU0"
"1","(-5950,4100)","0","mstr_symbols","I119";
;
HDL_POWER"PVCCIN_CPU0"
BODY_TYPE"PLUMBING"
CDS_LIB"mstr_symbols"
VOLTAGE"2.0V";
"G\NAC"6;
%"CAP"
"1","(-2850,950)","0","mstr_discrete","I12";
;
VOLTAGE"4V"
VALUE"47UF"
LOCATION"C4P9"
PACK_TYPE"0805"
GROUP"PWR_MLCC_CAP"
PART_NUMBER"C95333-006"
MATERIAL"X6S"
TOLERANCE"20%"
BOM_COST"PROC_SOCKET"
CDS_LIB"mstr_discrete"
CDS_SEC"1"
$SEC"1"
CDS_LOCATION"C4P9"
ROOM"PVCCIN_CPU0_DECAP_VR";
"A"
$PN"1"15;
"B"
$PN"2"18;
%"PVCCIN_CPU0"
"1","(-5950,3425)","0","mstr_symbols","I121";
;
HDL_POWER"PVCCIN_CPU0"
BODY_TYPE"PLUMBING"
CDS_LIB"mstr_symbols"
VOLTAGE"2.0V";
"G\NAC"7;
%"GND"
"1","(-7750,4225)","0","mstr_symbols","I122";
;
VOLTAGE"0"
SIZE"1B"
CDS_LIB"mstr_symbols"
BODY_TYPE"PLUMBING"
HDL_POWER"GND";
"A\NAC"8;
%"CAP_A"
"1","(-6750,3800)","0","dev_discrete","I123";
;
GROUP"PWR_MLCC_CAP"
LOCATION"C5D16"
VOLTAGE"4V"
TOLERANCE"20%"
MATERIAL"X6S"
PACK_TYPE"0603V"
PART_NUMBER"E15431-004"
VALUE"22.0UF"
CDS_LOCATION"C5D16"
BOM_COST"PROC_SOCKET"
CDS_LIB"dev_discrete"
CDS_SEC"1"
$SEC"1"
ROOM"PVCCIN_CPU0_DECAP_VR";
"B"
$PN"2"9;
"A"
$PN"1"1;
%"GND"
"1","(-7750,3525)","0","mstr_symbols","I124";
;
VOLTAGE"0"
SIZE"1B"
CDS_LIB"mstr_symbols"
BODY_TYPE"PLUMBING"
HDL_POWER"GND";
"A\NAC"9;
%"CAP_A"
"1","(-7050,4500)","0","dev_discrete","I125";
;
PACK_TYPE"0603V"
MATERIAL"X6S"
PART_NUMBER"E15431-004"
LOCATION"C5D5"
VALUE"22.0UF"
TOLERANCE"20%"
VOLTAGE"4V"
GROUP"PWR_MLCC_CAP"
CDS_LOCATION"C5D5"
BOM_COST"PROC_SOCKET"
CDS_LIB"dev_discrete"
CDS_SEC"1"
$SEC"1"
ROOM"PVCCIN_CPU0_DECAP_VR";
"B"
$PN"2"8;
"A"
$PN"1"11;
%"CAP_A"
"1","(-7050,3800)","0","dev_discrete","I128";
;
GROUP"PWR_MLCC_CAP"
PART_NUMBER"E15431-004"
MATERIAL"X6S"
TOLERANCE"20%"
PACK_TYPE"0603V"
LOCATION"C5D19"
VALUE"22.0UF"
VOLTAGE"4V"
CDS_LOCATION"C5D19"
BOM_COST"PROC_SOCKET"
CDS_LIB"dev_discrete"
CDS_SEC"1"
$SEC"1"
ROOM"PVCCIN_CPU0_DECAP_VR";
"B"
$PN"2"9;
"A"
$PN"1"1;
%"CAP_A"
"1","(-5950,3150)","0","dev_discrete","I131";
;
PART_NUMBER"E15431-004"
VOLTAGE"4V"
TOLERANCE"20%"
MATERIAL"X6S"
VALUE"22.0UF"
LOCATION"C5D43"
GROUP"PWR_MLCC_CAP"
PACK_TYPE"0603V"
CDS_LOCATION"C5D43"
BOM_COST"PROC_SOCKET"
CDS_LIB"dev_discrete"
CDS_SEC"1"
$SEC"1"
ROOM"PVCCIN_CPU0_DECAP_VR";
"B"
$PN"2"4;
"A"
$PN"1"7;
%"CAP_A"
"1","(-6650,3100)","0","dev_discrete","I132";
;
MATERIAL"X6S"
TOLERANCE"20%"
VOLTAGE"4V"
PACK_TYPE"0603V"
LOCATION"C5D15"
VALUE"22.0UF"
PART_NUMBER"E15431-004"
GROUP"PWR_MLCC_CAP"
ROOM"PVCCIN_CPU0_DECAP_VR"
$SEC"1"
CDS_SEC"1"
CDS_LIB"dev_discrete"
BOM_COST"PROC_SOCKET"
CDS_LOCATION"C5D15";
"B"
$PN"2"10;
"A"
$PN"1"12;
%"GND"
"1","(-7750,2825)","0","mstr_symbols","I133";
;
VOLTAGE"0"
SIZE"1B"
CDS_LIB"mstr_symbols"
BODY_TYPE"PLUMBING"
HDL_POWER"GND";
"A\NAC"10;
%"CAP_A"
"1","(-6950,3100)","0","dev_discrete","I134";
;
MATERIAL"X6S"
TOLERANCE"20%"
VOLTAGE"4V"
VALUE"22.0UF"
PART_NUMBER"E15431-004"
PACK_TYPE"0603V"
LOCATION"C5D18"
GROUP"PWR_MLCC_CAP"
CDS_LOCATION"C5D18"
BOM_COST"PROC_SOCKET"
CDS_LIB"dev_discrete"
CDS_SEC"1"
$SEC"1"
ROOM"PVCCIN_CPU0_DECAP_VR";
"B"
$PN"2"10;
"A"
$PN"1"12;
%"CAP_A"
"1","(-7250,3100)","0","dev_discrete","I135";
;
GROUP"PWR_MLCC_CAP"
PART_NUMBER"E15431-004"
PACK_TYPE"0603V"
VOLTAGE"4V"
LOCATION"C5D42"
VALUE"22.0UF"
MATERIAL"X6S"
TOLERANCE"20%"
ROOM"PVCCIN_CPU0_DECAP_VR"
$SEC"1"
CDS_SEC"1"
CDS_LIB"dev_discrete"
BOM_COST"PROC_SOCKET"
CDS_LOCATION"C5D42";
"B"
$PN"2"10;
"A"
$PN"1"12;
%"PVCCIN_CPU0"
"1","(-7750,4800)","0","mstr_symbols","I137";
;
VOLTAGE"2.0V"
CDS_LIB"mstr_symbols"
BODY_TYPE"PLUMBING"
HDL_POWER"PVCCIN_CPU0";
"G\NAC"11;
%"CAP_A"
"1","(-7750,4500)","0","dev_discrete","I138";
;
PACK_TYPE"0603V"
PART_NUMBER"E15431-004"
MATERIAL"X6S"
VALUE"22.0UF"
VOLTAGE"4V"
TOLERANCE"20%"
LOCATION"C5D24"
GROUP"PWR_MLCC_CAP"
CDS_LOCATION"C5D24"
BOM_COST"PROC_SOCKET"
CDS_LIB"dev_discrete"
CDS_SEC"1"
$SEC"1"
ROOM"PVCCIN_CPU0_DECAP_VR";
"B"
$PN"2"8;
"A"
$PN"1"11;
%"PVCCIN_CPU0"
"1","(-7750,4100)","0","mstr_symbols","I139";
;
VOLTAGE"2.0V"
CDS_LIB"mstr_symbols"
BODY_TYPE"PLUMBING"
HDL_POWER"PVCCIN_CPU0";
"G\NAC"1;
%"CAP_A"
"1","(-7750,3800)","0","dev_discrete","I140";
;
GROUP"PWR_MLCC_CAP"
PART_NUMBER"E15431-004"
LOCATION"C5D39"
MATERIAL"X6S"
PACK_TYPE"0603V"
VALUE"22.0UF"
VOLTAGE"4V"
TOLERANCE"20%"
CDS_LOCATION"C5D39"
BOM_COST"PROC_SOCKET"
CDS_LIB"dev_discrete"
CDS_SEC"1"
$SEC"1"
ROOM"PVCCIN_CPU0_DECAP_VR";
"B"
$PN"2"9;
"A"
$PN"1"1;
%"PVCCIN_CPU0"
"1","(-7750,3400)","0","mstr_symbols","I141";
;
HDL_POWER"PVCCIN_CPU0"
BODY_TYPE"PLUMBING"
CDS_LIB"mstr_symbols"
VOLTAGE"2.0V";
"G\NAC"12;
%"CAP_A"
"1","(-7750,3100)","0","dev_discrete","I142";
;
GROUP"PWR_MLCC_CAP"
LOCATION"C5D44"
VALUE"22.0UF"
VOLTAGE"4V"
TOLERANCE"20%"
MATERIAL"X6S"
PART_NUMBER"E15431-004"
PACK_TYPE"0603V"
CDS_LOCATION"C5D44"
BOM_COST"PROC_SOCKET"
CDS_LIB"dev_discrete"
CDS_SEC"1"
$SEC"1"
ROOM"PVCCIN_CPU0_DECAP_VR";
"B"
$PN"2"10;
"A"
$PN"1"12;
%"VCC_CORE"
"1","(-3550,4725)","0","mstr_symbols","I144";
;
HDL_POWER"PVCCMCP_CPU0"
CDS_LIB"mstr_symbols";
"A"13;
%"CAP_A"
"1","(-2850,3800)","0","dev_discrete","I145";
;
GROUP"PWR_MLCC_CAP"
PART_NUMBER"E15431-004"
MATERIAL"X6S"
VOLTAGE"4V"
TOLERANCE"20%"
PACK_TYPE"0603V"
VALUE"22.0UF"
LOCATION"C6D9"
ROOM"PVCCIN_CPU0_DECAP_VR"
$SEC"1"
CDS_SEC"1"
CDS_LIB"dev_discrete"
CDS_LOCATION"C6D9";
"B"
$PN"2"41;
"A"
$PN"1"42;
%"CAP_A"
"1","(-3100,3800)","0","dev_discrete","I147";
;
GROUP"PWR_MLCC_CAP"
PACK_TYPE"0603V"
PART_NUMBER"E15431-004"
TOLERANCE"20%"
MATERIAL"X6S"
VOLTAGE"4V"
VALUE"22.0UF"
LOCATION"C6D10"
ROOM"PVCCIN_CPU0_DECAP_VR"
$SEC"1"
CDS_SEC"1"
CDS_LIB"dev_discrete"
CDS_LOCATION"C6D10";
"B"
$PN"2"41;
"A"
$PN"1"42;
%"CAP_A"
"1","(-2300,4500)","0","dev_discrete","I151";
;
PACK_TYPE"0603V"
MATERIAL"X6S"
TOLERANCE"20%"
VOLTAGE"4V"
LOCATION"C5D36"
PART_NUMBER"E15431-004"
VALUE"22.0UF"
GROUP"PWR_MCP_CAP"
ROOM"PVCCIN_CPU0_DECAP_VR"
$SEC"1"
CDS_SEC"1"
CDS_LIB"dev_discrete"
BOM_COST"PROC_SOCKET"
CDS_LOCATION"C5D36";
"B"
$PN"2"40;
"A"
$PN"1"13;
%"CAP_A"
"1","(-2050,4500)","0","dev_discrete","I152";
;
VOLTAGE"4V"
TOLERANCE"20%"
PART_NUMBER"E15431-004"
PACK_TYPE"0603V"
LOCATION"C5D49"
MATERIAL"X6S"
VALUE"22.0UF"
GROUP"PWR_MCP_CAP"
CDS_LOCATION"C5D49"
BOM_COST"PROC_SOCKET"
CDS_LIB"dev_discrete"
CDS_SEC"1"
$SEC"1"
ROOM"PVCCIN_CPU0_DECAP_VR";
"B"
$PN"2"40;
"A"
$PN"1"13;
%"CAP_A"
"1","(-550,4500)","0","dev_discrete","I153";
;
PACK_TYPE"0603V"
PART_NUMBER"E15431-004"
GROUP"PWR_MCP_CAP"
LOCATION"C5D22"
VALUE"22.0UF"
VOLTAGE"4V"
TOLERANCE"20%"
MATERIAL"X6S"
ROOM"PVCCIN_CPU0_DECAP_VR"
$SEC"1"
CDS_SEC"1"
CDS_LIB"dev_discrete"
BOM_COST"PROC_SOCKET"
CDS_LOCATION"C5D22";
"B"
$PN"2"40;
"A"
$PN"1"13;
%"CAP_A"
"1","(-4450,4500)","0","dev_discrete","I154";
;
PACK_TYPE"0603V"
PART_NUMBER"E15431-004"
LOCATION"C5D26"
VOLTAGE"4V"
TOLERANCE"20%"
MATERIAL"X6S"
GROUP"PWR_MLCC_CAP"
VALUE"22.0UF"
CDS_LOCATION"C5D26"
BOM_COST"PROC_SOCKET"
CDS_LIB"dev_discrete"
CDS_SEC"1"
$SEC"1"
ROOM"PVCCIN_CPU0_DECAP_VR";
"B"
$PN"2"3;
"A"
$PN"1"5;
%"CAP_A"
"1","(-4600,3800)","0","dev_discrete","I155";
;
LOCATION"C5D25"
PACK_TYPE"0603V"
VALUE"22.0UF"
VOLTAGE"4V"
MATERIAL"X6S"
GROUP"PWR_MLCC_CAP"
PART_NUMBER"E15431-004"
TOLERANCE"20%"
ROOM"PVCCIN_CPU0_DECAP_VR"
$SEC"1"
CDS_SEC"1"
CDS_LIB"dev_discrete"
BOM_COST"PROC_SOCKET"
CDS_LOCATION"C5D25";
"B"
$PN"2"2;
"A"
$PN"1"6;
%"CAP_A"
"1","(-4700,3150)","0","dev_discrete","I156";
;
MATERIAL"X6S"
VOLTAGE"4V"
VALUE"22.0UF"
LOCATION"C5D45"
PACK_TYPE"0603V"
PART_NUMBER"E15431-004"
TOLERANCE"20%"
GROUP"PWR_MLCC_CAP"
ROOM"PVCCIN_CPU0_DECAP_VR"
$SEC"1"
CDS_SEC"1"
CDS_LIB"dev_discrete"
BOM_COST"PROC_SOCKET"
CDS_LOCATION"C5D45";
"B"
$PN"2"4;
"A"
$PN"1"7;
%"VCC_CORE"
"1","(-4750,2525)","0","mstr_symbols","I159";
;
HDL_POWER"PVCCMCP_CPU0"
CDS_LIB"mstr_symbols";
"A"14;
%"PVCCIO_CPU0"
"1","(-3200,1275)","0","mstr_symbols","I16";
;
HDL_POWER"PVCCIO_CPU0"
BODY_TYPE"PLUMBING"
CDS_LIB"mstr_symbols"
VOLTAGE"1.1V";
"G\NAC"15;
%"CAP_A"
"1","(-2250,950)","0","dev_discrete","I164";
;
VALUE"22.0UF"
TOLERANCE"20%"
VOLTAGE"4V"
PACK_TYPE"0603V"
PART_NUMBER"E15431-004"
MATERIAL"X6S"
GROUP"PWR_MLCC_CAP"
LOCATION"C4P6"
CDS_LOCATION"C4P6"
CDS_LIB"dev_discrete"
CDS_SEC"1"
$SEC"1"
ROOM"PVCCIN_CPU0_DECAP_VR";
"B"
$PN"2"18;
"A"
$PN"1"15;
%"CAP"
"1","(-3200,950)","0","mstr_discrete","I17";
;
VOLTAGE"4V"
VALUE"47UF"
LOCATION"C4P10"
TOLERANCE"20%"
MATERIAL"X6S"
PACK_TYPE"0805"
PART_NUMBER"C95333-006"
GROUP"PWR_MLCC_CAP"
ROOM"PVCCIN_CPU0_DECAP_VR"
CDS_LOCATION"C4P10"
$SEC"1"
CDS_SEC"1"
CDS_LIB"mstr_discrete"
BOM_COST"PROC_SOCKET";
"A"
$PN"1"15;
"B"
$PN"2"18;
%"CAP_A"
"1","(-1050,3850)","0","dev_discrete","I173";
;
TOLERANCE"20%"
PART_NUMBER"E15431-004"
PACK_TYPE"0603V"
LOCATION"C5D20"
MATERIAL"X6S"
VOLTAGE"4V"
VALUE"22.0UF"
GROUP"PWR_MCP_CAP"
ROOM"PVCCIN_CPU0_DECAP_VR"
$SEC"1"
CDS_SEC"1"
CDS_LIB"dev_discrete"
BOM_COST"PROC_SOCKET"
CDS_LOCATION"C5D20";
"B"
$PN"2"28;
"A"
$PN"1"16;
%"CAP_A"
"1","(-800,3850)","0","dev_discrete","I174";
;
LOCATION"C5D33"
VALUE"22.0UF"
TOLERANCE"20%"
MATERIAL"X6S"
PACK_TYPE"0603V"
PART_NUMBER"E15431-004"
VOLTAGE"4V"
GROUP"PWR_MCP_CAP"
CDS_LOCATION"C5D33"
BOM_COST"PROC_SOCKET"
CDS_LIB"dev_discrete"
CDS_SEC"1"
$SEC"1"
ROOM"PVCCIN_CPU0_DECAP_VR";
"B"
$PN"2"28;
"A"
$PN"1"16;
%"CAP_A"
"1","(-550,3850)","0","dev_discrete","I175";
;
LOCATION"C5D34"
VALUE"22.0UF"
PACK_TYPE"0603V"
VOLTAGE"4V"
TOLERANCE"20%"
MATERIAL"X6S"
PART_NUMBER"E15431-004"
GROUP"PWR_MCP_CAP"
CDS_LOCATION"C5D34"
BOM_COST"PROC_SOCKET"
CDS_LIB"dev_discrete"
CDS_SEC"1"
$SEC"1"
ROOM"PVCCIN_CPU0_DECAP_VR";
"B"
$PN"2"28;
"A"
$PN"1"16;
%"CAP_A"
"1","(-1300,3850)","0","dev_discrete","I176";
;
MATERIAL"X6S"
PART_NUMBER"E15431-004"
GROUP"PWR_MCP_CAP"
TOLERANCE"20%"
VOLTAGE"4V"
LOCATION"C5D35"
VALUE"22.0UF"
PACK_TYPE"0603V"
ROOM"PVCCIN_CPU0_DECAP_VR"
$SEC"1"
CDS_SEC"1"
CDS_LIB"dev_discrete"
BOM_COST"PROC_SOCKET"
CDS_LOCATION"C5D35";
"B"
$PN"2"28;
"A"
$PN"1"16;
%"CAP_A"
"1","(-1950,950)","0","dev_discrete","I178";
;
VALUE"22.0UF"
VOLTAGE"4V"
TOLERANCE"20%"
MATERIAL"X6S"
PART_NUMBER"E15431-004"
PACK_TYPE"0603V"
LOCATION"C4P8"
GROUP"PWR_MLCC_CAP"
CDS_LOCATION"C4P8"
CDS_LIB"dev_discrete"
CDS_SEC"1"
$SEC"1"
ROOM"PVCCIN_CPU0_DECAP_VR";
"B"
$PN"2"18;
"A"
$PN"1"15;
%"CAP_A"
"1","(-1550,3850)","0","dev_discrete","I179";
;
LOCATION"C5D53"
VOLTAGE"4V"
VALUE"22.0UF"
GROUP"PWR_MCP_CAP"
PACK_TYPE"0603V"
PART_NUMBER"E15431-004"
MATERIAL"X6S"
TOLERANCE"20%"
ROOM"PVCCIN_CPU0_DECAP_VR"
$SEC"1"
CDS_SEC"1"
CDS_LIB"dev_discrete"
CDS_LOCATION"C5D53";
"B"
$PN"2"28;
"A"
$PN"1"16;
%"CAP_A"
"1","(-1800,3850)","0","dev_discrete","I180";
;
GROUP"PWR_MCP_CAP"
MATERIAL"X6S"
PART_NUMBER"E15431-004"
VALUE"22.0UF"
LOCATION"C5D52"
PACK_TYPE"0603V"
TOLERANCE"20%"
VOLTAGE"4V"
ROOM"PVCCIN_CPU0_DECAP_VR"
$SEC"1"
CDS_SEC"1"
CDS_LIB"dev_discrete"
CDS_LOCATION"C5D52";
"B"
$PN"2"28;
"A"
$PN"1"16;
%"VCC_CORE"
"1","(-1800,4075)","0","mstr_symbols","I181";
;
HDL_POWER"PVCCMCP_CPU0"
CDS_LIB"mstr_symbols";
"A"16;
%"CAP"
"1","(-6850,1550)","0","mstr_discrete","I187";
;
CDS_SEC"1"
GROUP"PWR_MLCC_CAP"
LOCATION"C5P15"
PACK_TYPE"0805"
PART_NUMBER"C95333-006"
TOLERANCE"20%"
VALUE"47UF"
MATERIAL"X6S"
VOLTAGE"4V"
SEC_TYPE"0805"
SEC"1"
BOM_COST"PROC_SOCKET"
CDS_LIB"mstr_discrete"
CDS_LOCATION"C5P15"
ROOM"PVCCIN_CPU0_DECAP_VR";
"A"
$PN"1"39;
"B"
$PN"2"35;
%"CAP"
"1","(-6850,2250)","0","mstr_discrete","I188";
;
CDS_SEC"1"
MATERIAL"X6S"
PACK_TYPE"0805"
TOLERANCE"20%"
VOLTAGE"4V"
LOCATION"C5P16"
GROUP"PWR_MLCC_CAP"
VALUE"47UF"
PART_NUMBER"C95333-006"
SEC_TYPE"0805"
SEC"1"
ROOM"PVCCIN_CPU0_DECAP_VR"
CDS_LOCATION"C5P16"
CDS_LIB"mstr_discrete"
BOM_COST"PROC_SOCKET";
"A"
$PN"1"38;
"B"
$PN"2"34;
%"CAP"
"1","(-6550,1550)","0","mstr_discrete","I190";
;
CDS_SEC"1"
LOCATION"C5P17"
VALUE"47UF"
PART_NUMBER"C95333-006"
PACK_TYPE"0805"
MATERIAL"X6S"
TOLERANCE"20%"
VOLTAGE"4V"
GROUP"PWR_MLCC_CAP"
ROOM"PVCCIN_CPU0_DECAP_VR"
CDS_LOCATION"C5P17"
CDS_LIB"mstr_discrete"
BOM_COST"PROC_SOCKET"
SEC"1"
SEC_TYPE"0805";
"A"
$PN"1"39;
"B"
$PN"2"35;
%"PVCCIN_CPU0"
"1","(-6550,1150)","0","mstr_symbols","I196";
;
VOLTAGE"2.0V"
CDS_LIB"mstr_symbols"
BODY_TYPE"PLUMBING"
HDL_POWER"PVCCIN_CPU0";
"G\NAC"17;
%"GND"
"1","(-1950,625)","0","mstr_symbols","I20";
;
VOLTAGE"0"
SIZE"1B"
CDS_LIB"mstr_symbols"
BODY_TYPE"PLUMBING"
HDL_POWER"GND";
"A\NAC"18;
%"PVCCIN_CPU0"
"1","(-5350,2550)","0","mstr_symbols","I203";
;
VOLTAGE"2.0V"
CDS_LIB"mstr_symbols"
BODY_TYPE"PLUMBING"
HDL_POWER"PVCCIN_CPU0";
"G\NAC"19;
%"GND"
"1","(-5950,1275)","0","mstr_symbols","I206";
;
HDL_POWER"GND"
BODY_TYPE"PLUMBING"
SIZE"1B"
CDS_LIB"mstr_symbols"
VOLTAGE"0";
"A\NAC"20;
%"PVCCIN_CPU0"
"1","(-5050,1850)","0","mstr_symbols","I208";
;
HDL_POWER"PVCCIN_CPU0"
BODY_TYPE"PLUMBING"
CDS_LIB"mstr_symbols"
VOLTAGE"2.0V";
"G\NAC"21;
%"GND"
"1","(-3850,625)","0","mstr_symbols","I21";
;
HDL_POWER"GND"
BODY_TYPE"PLUMBING"
SIZE"1B"
CDS_LIB"mstr_symbols"
VOLTAGE"0";
"A\NAC"22;
%"GND"
"1","(-5350,1975)","0","mstr_symbols","I210";
;
HDL_POWER"GND"
BODY_TYPE"PLUMBING"
CDS_LIB"mstr_symbols"
SIZE"1B"
VOLTAGE"0";
"A\NAC"23;
%"CAP"
"1","(-1150,1250)","0","mstr_discrete","I211";
;
PACK_TYPE"0805"
TOLERANCE"20%"
VOLTAGE"4V"
GROUP"PWR_MLCC_CAP"
NEW_MATERIAL"X6S"
VALUE"100UF"
LOCATION"C8W3"
NEW_PN"078.1071T.M002"
PART_NUMBER"602433-112"
CDS_LOCATION"C8W3"
CDS_SEC"1"
CDS_LIB"mstr_discrete"
BOM_COST"MEM_VRD_PVDDQ_CD"
ROOM"VDDQ_ABC_PWR_VR"
SEC_TYPE"0805"
SEC"1"
MATERIAL"X5R";
"A"
$PN"1"25;
"B"
$PN"2"24;
%"GND"
"1","(-1150,1025)","0","mstr_symbols","I212";
;
HDL_POWER"GND"
BODY_TYPE"PLUMBING"
SIZE"1B"
CDS_LIB"mstr_symbols"
VOLTAGE"0";
"A\NAC"24;
%"PVCCIN_CPU0"
"1","(-1150,1500)","0","mstr_symbols","I213";
;
VOLTAGE"2.0V"
CDS_LIB"mstr_symbols"
BODY_TYPE"PLUMBING"
HDL_POWER"PVCCIN_CPU0";
"G\NAC"25;
%"CAP"
"1","(-4150,950)","0","mstr_discrete","I214";
;
MATERIAL"X6S"
TOLERANCE"20%"
VOLTAGE"4V"
LOCATION"C5P8"
VALUE"22UF"
GROUP"PWR_MLCC_CAP"
PACK_TYPE"0805LF"
PART_NUMBER"C95333-002"
ROOM"PVCCIN_CPU0_DECAP_VR"
$SEC"1"
CDS_SEC"1"
BOM_COST"PROC_SOCKET"
CDS_LIB"mstr_discrete"
CDS_LOCATION"C5P8";
"A"
$PN"1"29;
"B"
$PN"2"22;
%"CAP"
"1","(-3850,950)","0","mstr_discrete","I215";
;
PACK_TYPE"0805LF"
MATERIAL"X6S"
GROUP"PWR_MLCC_CAP"
PART_NUMBER"C95333-002"
TOLERANCE"20%"
VOLTAGE"4V"
VALUE"22UF"
LOCATION"C5P9"
ROOM"PVCCIN_CPU0_DECAP_VR"
$SEC"1"
CDS_SEC"1"
BOM_COST"PROC_SOCKET"
CDS_LIB"mstr_discrete"
CDS_LOCATION"C5P9";
"A"
$PN"1"29;
"B"
$PN"2"22;
%"VCC_CORE"
"1","(-800,3375)","0","mstr_symbols","I216";
;
HDL_POWER"PVCCMCP_CPU0"
CDS_LIB"mstr_symbols";
"A"26;
%"CAP_A"
"1","(-800,3150)","0","dev_discrete","I217";
;
CDS_SEC"1"
GROUP"PWR_MCP_CAP"
LOCATION"C5W1"
VALUE"22.0UF"
MATERIAL"X6S"
PART_NUMBER"E15431-004"
PACK_TYPE"0603V"
TOLERANCE"20%"
VOLTAGE"4V"
CDS_LOCATION"C5W1"
SEC_TYPE"0603V"
SEC"1"
BOM_COST"PROC_SOCKET"
CDS_LIB"dev_discrete"
ROOM"PVCCIN_CPU0_DECAP_VR";
"B"
$PN"2"27;
"A"
$PN"1"26;
%"CAP_A"
"1","(-550,3150)","0","dev_discrete","I218";
;
CDS_SEC"1"
PART_NUMBER"E15431-004"
GROUP"PWR_MCP_CAP"
VALUE"22.0UF"
LOCATION"C5W2"
TOLERANCE"20%"
MATERIAL"X6S"
VOLTAGE"4V"
PACK_TYPE"0603V"
ROOM"PVCCIN_CPU0_DECAP_VR"
CDS_LIB"dev_discrete"
BOM_COST"PROC_SOCKET"
SEC"1"
SEC_TYPE"0603V"
CDS_LOCATION"C5W2";
"B"
$PN"2"27;
"A"
$PN"1"26;
%"GND"
"1","(-800,2875)","0","mstr_symbols","I219";
;
VOLTAGE"0"
SIZE"1B"
CDS_LIB"mstr_symbols"
BODY_TYPE"PLUMBING"
HDL_POWER"GND";
"A\NAC"27;
%"CAP"
"1","(-4750,2225)","0","mstr_discrete","I220";
;
NEW_MATERIAL"X6S"
NEW_PN"078.1071T.M002"
VALUE"100UF"
LOCATION"C5P29"
VOLTAGE"4V"
TOLERANCE"20%"
PART_NUMBER"602433-112"
PACK_TYPE"0805"
GROUP"PWR_MCP_CAP"
MATERIAL"X5R"
SEC"1"
SEC_TYPE"0805"
ROOM"VDDQ_ABC_PWR_VR"
BOM_COST"MEM_VRD_PVDDQ_CD"
CDS_LIB"mstr_discrete"
CDS_SEC"1"
CDS_LOCATION"C5P29";
"A"
$PN"1"14;
"B"
$PN"2"36;
%"CAP"
"1","(-4500,2225)","0","mstr_discrete","I221";
;
NEW_PN"078.1071T.M002"
LOCATION"C5P30"
VALUE"100UF"
PACK_TYPE"0805"
VOLTAGE"4V"
PART_NUMBER"602433-112"
TOLERANCE"20%"
GROUP"PWR_MCP_CAP"
NEW_MATERIAL"X6S"
CDS_LOCATION"C5P30"
MATERIAL"X5R"
SEC"1"
SEC_TYPE"0805"
ROOM"VDDQ_ABC_PWR_VR"
BOM_COST"MEM_VRD_PVDDQ_CD"
CDS_LIB"mstr_discrete"
CDS_SEC"1";
"A"
$PN"1"14;
"B"
$PN"2"36;
%"CAP"
"1","(-4000,2225)","0","mstr_discrete","I222";
;
NEW_PN"078.1071T.M002"
PACK_TYPE"0805"
TOLERANCE"20%"
GROUP"PWR_MCP_CAP"
LOCATION"C5P19"
VALUE"100UF"
PART_NUMBER"602433-112"
VOLTAGE"4V"
NEW_MATERIAL"X6S"
CDS_LOCATION"C5P19"
CDS_SEC"1"
CDS_LIB"mstr_discrete"
BOM_COST"MEM_VRD_PVDDQ_CD"
ROOM"VDDQ_ABC_PWR_VR"
SEC_TYPE"0805"
SEC"1"
MATERIAL"X5R";
"A"
$PN"1"14;
"B"
$PN"2"36;
%"CAP"
"1","(-4250,2225)","0","mstr_discrete","I223";
;
NEW_MATERIAL"X6S"
NEW_PN"078.1071T.M002"
LOCATION"C4P4"
PACK_TYPE"0805"
TOLERANCE"20%"
VALUE"100UF"
PART_NUMBER"602433-112"
VOLTAGE"4V"
GROUP"PWR_MCP_CAP"
MATERIAL"X5R"
SEC"1"
SEC_TYPE"0805"
ROOM"VDDQ_ABC_PWR_VR"
BOM_COST"MEM_VRD_PVDDQ_CD"
CDS_LIB"mstr_discrete"
CDS_SEC"1"
CDS_LOCATION"C4P4";
"A"
$PN"1"14;
"B"
$PN"2"36;
%"CAP"
"1","(-3750,2225)","0","mstr_discrete","I224";
;
PACK_TYPE"0805"
TOLERANCE"20%"
LOCATION"C4P7"
VOLTAGE"4V"
PART_NUMBER"602433-112"
VALUE"100UF"
NEW_MATERIAL"X6S"
GROUP"PWR_MCP_CAP"
NEW_PN"078.1071T.M002"
CDS_SEC"1"
CDS_LIB"mstr_discrete"
BOM_COST"MEM_VRD_PVDDQ_CD"
ROOM"VDDQ_ABC_PWR_VR"
SEC_TYPE"0805"
SEC"1"
MATERIAL"X5R"
CDS_LOCATION"C4P7";
"A"
$PN"1"14;
"B"
$PN"2"36;
%"CAP"
"1","(-3500,2225)","0","mstr_discrete","I225";
;
LOCATION"C4P3"
PART_NUMBER"602433-112"
VOLTAGE"4V"
TOLERANCE"20%"
PACK_TYPE"0805"
NEW_PN"078.1071T.M002"
NEW_MATERIAL"X6S"
GROUP"PWR_MCP_CAP"
VALUE"100UF"
CDS_LOCATION"C4P3"
CDS_SEC"1"
CDS_LIB"mstr_discrete"
BOM_COST"MEM_VRD_PVDDQ_CD"
ROOM"VDDQ_ABC_PWR_VR"
SEC_TYPE"0805"
SEC"1"
MATERIAL"X5R";
"A"
$PN"1"14;
"B"
$PN"2"36;
%"CAP"
"1","(-3250,2225)","0","mstr_discrete","I226";
;
LOCATION"C5P10"
VALUE"100UF"
VOLTAGE"4V"
TOLERANCE"20%"
GROUP"PWR_MCP_CAP"
NEW_MATERIAL"X6S"
NEW_PN"078.1071T.M002"
PACK_TYPE"0805"
PART_NUMBER"602433-112"
MATERIAL"X5R"
SEC"1"
SEC_TYPE"0805"
ROOM"VDDQ_ABC_PWR_VR"
BOM_COST"MEM_VRD_PVDDQ_CD"
CDS_LIB"mstr_discrete"
CDS_SEC"1"
CDS_LOCATION"C5P10";
"A"
$PN"1"14;
"B"
$PN"2"36;
%"CAP"
"1","(-3000,2225)","0","mstr_discrete","I227";
;
VOLTAGE"4V"
PART_NUMBER"602433-112"
VALUE"100UF"
LOCATION"C5P11"
PACK_TYPE"0805"
TOLERANCE"20%"
GROUP"PWR_MCP_CAP"
NEW_MATERIAL"X6S"
NEW_PN"078.1071T.M002"
CDS_LOCATION"C5P11"
CDS_SEC"1"
CDS_LIB"mstr_discrete"
BOM_COST"MEM_VRD_PVDDQ_CD"
ROOM"VDDQ_ABC_PWR_VR"
SEC_TYPE"0805"
SEC"1"
MATERIAL"X5R";
"A"
$PN"1"14;
"B"
$PN"2"36;
%"CAP"
"1","(-2500,2225)","0","mstr_discrete","I228";
;
NEW_PN"078.1071T.M002"
LOCATION"C5P18"
VALUE"100UF"
PACK_TYPE"0805"
TOLERANCE"20%"
VOLTAGE"4V"
PART_NUMBER"602433-112"
NEW_MATERIAL"X6S"
GROUP"PWR_MCP_CAP"
CDS_LOCATION"C5P18"
CDS_SEC"1"
CDS_LIB"mstr_discrete"
BOM_COST"MEM_VRD_PVDDQ_CD"
ROOM"VDDQ_ABC_PWR_VR"
SEC_TYPE"0805"
SEC"1"
MATERIAL"X5R";
"A"
$PN"1"14;
"B"
$PN"2"36;
%"CAP"
"1","(-2750,2225)","0","mstr_discrete","I229";
;
NEW_PN"078.1071T.M002"
GROUP"PWR_MCP_CAP"
PACK_TYPE"0805"
TOLERANCE"20%"
PART_NUMBER"602433-112"
LOCATION"C5P28"
VALUE"100UF"
VOLTAGE"4V"
NEW_MATERIAL"X6S"
MATERIAL"X5R"
SEC"1"
SEC_TYPE"0805"
ROOM"VDDQ_ABC_PWR_VR"
BOM_COST"MEM_VRD_PVDDQ_CD"
CDS_LIB"mstr_discrete"
CDS_SEC"1"
CDS_LOCATION"C5P28";
"A"
$PN"1"14;
"B"
$PN"2"36;
%"CAP"
"1","(-2000,2225)","0","mstr_discrete","I230";
;
PART_NUMBER"602433-112"
VOLTAGE"4V"
TOLERANCE"20%"
VALUE"100UF"
PACK_TYPE"0805"
LOCATION"C4P2"
NEW_PN"078.1071T.M002"
NEW_MATERIAL"X6S"
GROUP"PWR_MCP_CAP"
CDS_LOCATION"C4P2"
MATERIAL"X5R"
SEC"1"
SEC_TYPE"0805"
ROOM"VDDQ_ABC_PWR_VR"
BOM_COST"MEM_VRD_PVDDQ_CD"
CDS_LIB"mstr_discrete"
CDS_SEC"1";
"A"
$PN"1"14;
"B"
$PN"2"36;
%"CAP"
"1","(-2250,2225)","0","mstr_discrete","I231";
;
NEW_PN"078.1071T.M002"
PART_NUMBER"602433-112"
VALUE"100UF"
LOCATION"C5P31"
VOLTAGE"4V"
PACK_TYPE"0805"
NEW_MATERIAL"X6S"
GROUP"PWR_MCP_CAP"
TOLERANCE"20%"
CDS_SEC"1"
CDS_LIB"mstr_discrete"
BOM_COST"MEM_VRD_PVDDQ_CD"
ROOM"VDDQ_ABC_PWR_VR"
SEC_TYPE"0805"
SEC"1"
MATERIAL"X5R"
CDS_LOCATION"C5P31";
"A"
$PN"1"14;
"B"
$PN"2"36;
%"CAP"
"1","(-1500,2225)","0","mstr_discrete","I232";
;
NEW_PN"078.1071T.M002"
GROUP"PWR_MCP_CAP"
VALUE"100UF"
PACK_TYPE"0805"
LOCATION"C5P13"
TOLERANCE"20%"
PART_NUMBER"602433-112"
VOLTAGE"4V"
NEW_MATERIAL"X6S"
MATERIAL"X5R"
SEC"1"
SEC_TYPE"0805"
ROOM"VDDQ_ABC_PWR_VR"
BOM_COST"MEM_VRD_PVDDQ_CD"
CDS_LIB"mstr_discrete"
CDS_SEC"1"
CDS_LOCATION"C5P13";
"A"
$PN"1"14;
"B"
$PN"2"36;
%"CAP"
"1","(-1750,2225)","0","mstr_discrete","I233";
;
NEW_PN"078.1071T.M002"
PACK_TYPE"0805"
VALUE"100UF"
PART_NUMBER"602433-112"
VOLTAGE"4V"
TOLERANCE"20%"
NEW_MATERIAL"X6S"
LOCATION"C4P5"
GROUP"PWR_MCP_CAP"
CDS_LOCATION"C4P5"
MATERIAL"X5R"
SEC"1"
SEC_TYPE"0805"
ROOM"VDDQ_ABC_PWR_VR"
BOM_COST"MEM_VRD_PVDDQ_CD"
CDS_LIB"mstr_discrete"
CDS_SEC"1";
"A"
$PN"1"14;
"B"
$PN"2"36;
%"CAP"
"1","(-1250,2225)","0","mstr_discrete","I234";
;
NEW_PN"078.1071T.M002"
TOLERANCE"20%"
NEW_MATERIAL"X6S"
LOCATION"C5P20"
PART_NUMBER"602433-112"
VOLTAGE"4V"
VALUE"100UF"
PACK_TYPE"0805"
GROUP"PWR_MCP_CAP"
MATERIAL"X5R"
SEC"1"
SEC_TYPE"0805"
ROOM"VDDQ_ABC_PWR_VR"
BOM_COST"MEM_VRD_PVDDQ_CD"
CDS_LIB"mstr_discrete"
CDS_SEC"1"
CDS_LOCATION"C5P20";
"A"
$PN"1"14;
"B"
$PN"2"36;
%"CAP"
"1","(-1000,2225)","0","mstr_discrete","I235";
;
NEW_MATERIAL"X6S"
PACK_TYPE"0805"
TOLERANCE"20%"
VOLTAGE"4V"
PART_NUMBER"602433-112"
LOCATION"C5P21"
VALUE"100UF"
GROUP"PWR_MCP_CAP"
NEW_PN"078.1071T.M002"
CDS_LOCATION"C5P21"
CDS_SEC"1"
CDS_LIB"mstr_discrete"
BOM_COST"MEM_VRD_PVDDQ_CD"
ROOM"VDDQ_ABC_PWR_VR"
SEC_TYPE"0805"
SEC"1"
MATERIAL"X5R";
"A"
$PN"1"14;
"B"
$PN"2"36;
%"CAP"
"1","(-750,2225)","0","mstr_discrete","I236";
;
PACK_TYPE"0805"
LOCATION"C5P12"
VALUE"100UF"
VOLTAGE"4V"
TOLERANCE"20%"
NEW_MATERIAL"X6S"
GROUP"PWR_MCP_CAP"
PART_NUMBER"602433-112"
NEW_PN"078.1071T.M002"
CDS_LOCATION"C5P12"
MATERIAL"X5R"
SEC"1"
SEC_TYPE"0805"
ROOM"VDDQ_ABC_PWR_VR"
BOM_COST"MEM_VRD_PVDDQ_CD"
CDS_LIB"mstr_discrete"
CDS_SEC"1";
"A"
$PN"1"14;
"B"
$PN"2"36;
%"GND"
"1","(-1800,3575)","0","mstr_symbols","I237";
;
HDL_POWER"GND"
BODY_TYPE"PLUMBING"
CDS_LIB"mstr_symbols"
SIZE"1B"
VOLTAGE"0";
"A\NAC"28;
%"PVSA_CPU0"
"1","(-4450,1250)","0","mstr_symbols","I24";
;
HDL_POWER"PVSA_CPU0"
BODY_TYPE"PLUMBING"
CDS_LIB"mstr_symbols"
VOLTAGE"1.1V";
"G\NAC"29;
%"CAP"
"1","(-4450,950)","0","mstr_discrete","I25";
;
PART_NUMBER"C95333-002"
MATERIAL"X6S"
PACK_TYPE"0805LF"
VALUE"22UF"
VOLTAGE"4V"
TOLERANCE"20%"
LOCATION"C5P7"
GROUP"PWR_MLCC_CAP"
CDS_LIB"mstr_discrete"
BOM_COST"PROC_SOCKET"
CDS_SEC"1"
$SEC"1"
CDS_LOCATION"C5P7"
ROOM"PVCCIN_CPU0_DECAP_VR";
"A"
$PN"1"29;
"B"
$PN"2"22;
%"CAP"
"1","(-5350,2250)","0","mstr_discrete","I28";
;
VOLTAGE"4V"
LOCATION"C5P23"
PART_NUMBER"C95333-006"
TOLERANCE"20%"
MATERIAL"X6S"
VALUE"47UF"
GROUP"PWR_MLCC_CAP"
PACK_TYPE"0805"
ROOM"PVCCIN_CPU0_DECAP_VR"
CDS_LOCATION"C5P23"
$SEC"1"
CDS_SEC"1"
BOM_COST"PROC_SOCKET"
CDS_LIB"mstr_discrete";
"A"
$PN"1"19;
"B"
$PN"2"23;
%"GND"
"1","(-5050,1275)","0","mstr_symbols","I32";
;
VOLTAGE"0"
CDS_LIB"mstr_symbols"
SIZE"1B"
BODY_TYPE"PLUMBING"
HDL_POWER"GND";
"A\NAC"30;
%"CAP"
"1","(-5050,1550)","0","mstr_discrete","I33";
;
VOLTAGE"4V"
VALUE"47UF"
TOLERANCE"20%"
MATERIAL"X6S"
PACK_TYPE"0805"
PART_NUMBER"C95333-006"
GROUP"PWR_MLCC_CAP"
LOCATION"C5P24"
ROOM"PVCCIN_CPU0_DECAP_VR"
CDS_LOCATION"C5P24"
$SEC"1"
CDS_SEC"1"
BOM_COST"PROC_SOCKET"
CDS_LIB"mstr_discrete";
"A"
$PN"1"21;
"B"
$PN"2"30;
%"GND"
"1","(-5350,575)","0","mstr_symbols","I35";
;
HDL_POWER"GND"
BODY_TYPE"PLUMBING"
CDS_LIB"mstr_symbols"
SIZE"1B"
VOLTAGE"0";
"A\NAC"31;
%"CAP"
"1","(-5350,850)","0","mstr_discrete","I37";
;
GROUP"PWR_MLCC_CAP"
PART_NUMBER"C95333-006"
VALUE"47UF"
LOCATION"C5P25"
VOLTAGE"4V"
PACK_TYPE"0805"
MATERIAL"X6S"
TOLERANCE"20%"
BOM_COST"PROC_SOCKET"
CDS_LIB"mstr_discrete"
CDS_SEC"1"
$SEC"1"
CDS_LOCATION"C5P25"
ROOM"PVCCIN_CPU0_DECAP_VR";
"A"
$PN"1"33;
"B"
$PN"2"31;
%"CAP"
"1","(-6550,2250)","0","mstr_discrete","I41";
;
PACK_TYPE"0805"
MATERIAL"X6S"
VOLTAGE"4V"
VALUE"47UF"
LOCATION"C5P14"
GROUP"PWR_MLCC_CAP"
TOLERANCE"20%"
PART_NUMBER"C95333-006"
ROOM"PVCCIN_CPU0_DECAP_VR"
CDS_LOCATION"C5P14"
$SEC"1"
CDS_SEC"1"
CDS_LIB"mstr_discrete"
BOM_COST"PROC_SOCKET";
"A"
$PN"1"38;
"B"
$PN"2"34;
%"PVCCIN_CPU0"
"1","(-5950,1850)","0","mstr_symbols","I43";
;
HDL_POWER"PVCCIN_CPU0"
BODY_TYPE"PLUMBING"
CDS_LIB"mstr_symbols"
VOLTAGE"2.0V";
"G\NAC"32;
%"CAP"
"1","(-5950,1550)","0","mstr_discrete","I44";
;
PART_NUMBER"C95333-006"
VOLTAGE"4V"
VALUE"47UF"
LOCATION"C5P27"
GROUP"PWR_MLCC_CAP"
PACK_TYPE"0805"
MATERIAL"X6S"
TOLERANCE"20%"
ROOM"PVCCIN_CPU0_DECAP_VR"
CDS_LOCATION"C5P27"
$SEC"1"
CDS_SEC"1"
BOM_COST"PROC_SOCKET"
CDS_LIB"mstr_discrete";
"A"
$PN"1"32;
"B"
$PN"2"20;
%"PVCCIN_CPU0"
"1","(-5950,1150)","0","mstr_symbols","I45";
;
HDL_POWER"PVCCIN_CPU0"
BODY_TYPE"PLUMBING"
CDS_LIB"mstr_symbols"
VOLTAGE"2.0V";
"G\NAC"33;
%"GND"
"1","(-7750,1975)","0","mstr_symbols","I46";
;
VOLTAGE"0"
CDS_LIB"mstr_symbols"
SIZE"1B"
BODY_TYPE"PLUMBING"
HDL_POWER"GND";
"A\NAC"34;
%"GND"
"1","(-7750,1275)","0","mstr_symbols","I48";
;
VOLTAGE"0"
CDS_LIB"mstr_symbols"
SIZE"1B"
BODY_TYPE"PLUMBING"
HDL_POWER"GND";
"A\NAC"35;
%"GND"
"1","(-750,1925)","0","mstr_symbols","I5";
;
VOLTAGE"0"
CDS_LIB"mstr_symbols"
SIZE"1B"
BODY_TYPE"PLUMBING"
HDL_POWER"GND";
"A\NAC"36;
%"CAP"
"1","(-7150,2250)","0","mstr_discrete","I50";
;
GROUP"PWR_MLCC_CAP"
PACK_TYPE"0805"
MATERIAL"X6S"
VOLTAGE"4V"
VALUE"47UF"
LOCATION"C5P33"
PART_NUMBER"C95333-006"
TOLERANCE"20%"
ROOM"PVCCIN_CPU0_DECAP_VR"
CDS_LOCATION"C5P33"
$SEC"1"
CDS_SEC"1"
CDS_LIB"mstr_discrete"
BOM_COST"PROC_SOCKET";
"A"
$PN"1"38;
"B"
$PN"2"34;
%"CAP"
"1","(-7450,2250)","0","mstr_discrete","I51";
;
GROUP"PWR_MLCC_CAP"
VOLTAGE"4V"
PACK_TYPE"0805"
MATERIAL"X6S"
LOCATION"C5P35"
VALUE"47UF"
PART_NUMBER"C95333-006"
TOLERANCE"20%"
BOM_COST"PROC_SOCKET"
CDS_LIB"mstr_discrete"
CDS_SEC"1"
$SEC"1"
CDS_LOCATION"C5P35"
ROOM"PVCCIN_CPU0_DECAP_VR";
"A"
$PN"1"38;
"B"
$PN"2"34;
%"CAP"
"1","(-7150,1550)","0","mstr_discrete","I53";
;
GROUP"PWR_MLCC_CAP"
PART_NUMBER"C95333-006"
PACK_TYPE"0805"
LOCATION"C5P32"
VALUE"47UF"
VOLTAGE"4V"
MATERIAL"X6S"
TOLERANCE"20%"
ROOM"PVCCIN_CPU0_DECAP_VR"
CDS_LOCATION"C5P32"
$SEC"1"
CDS_SEC"1"
CDS_LIB"mstr_discrete"
BOM_COST"PROC_SOCKET";
"A"
$PN"1"39;
"B"
$PN"2"35;
%"CAP"
"1","(-7450,1550)","0","mstr_discrete","I54";
;
GROUP"PWR_MLCC_CAP"
PACK_TYPE"0805"
MATERIAL"X6S"
TOLERANCE"20%"
VOLTAGE"4V"
VALUE"47UF"
LOCATION"C5P34"
PART_NUMBER"C95333-006"
BOM_COST"PROC_SOCKET"
CDS_LIB"mstr_discrete"
CDS_SEC"1"
$SEC"1"
CDS_LOCATION"C5P34"
ROOM"PVCCIN_CPU0_DECAP_VR";
"A"
$PN"1"39;
"B"
$PN"2"35;
%"CAP"
"1","(-5650,850)","0","mstr_discrete","I55";
;
GROUP"PWR_MLCC_CAP"
PART_NUMBER"C95333-006"
VALUE"47UF"
VOLTAGE"4V"
MATERIAL"X6S"
TOLERANCE"20%"
LOCATION"C5P22"
PACK_TYPE"0805"
BOM_COST"PROC_SOCKET"
CDS_LIB"mstr_discrete"
CDS_SEC"1"
$SEC"1"
CDS_LOCATION"C5P22"
ROOM"PVCCIN_CPU0_DECAP_VR";
"A"
$PN"1"33;
"B"
$PN"2"31;
%"CAP"
"1","(-5950,850)","0","mstr_discrete","I56";
;
LOCATION"C5P26"
VALUE"47UF"
PART_NUMBER"C95333-006"
MATERIAL"X6S"
VOLTAGE"4V"
TOLERANCE"20%"
PACK_TYPE"0805"
GROUP"PWR_MLCC_CAP"
ROOM"PVCCIN_CPU0_DECAP_VR"
CDS_LOCATION"C5P26"
$SEC"1"
CDS_SEC"1"
CDS_LIB"mstr_discrete"
BOM_COST"PROC_SOCKET";
"A"
$PN"1"33;
"B"
$PN"2"31;
%"CAP"
"1","(-6550,850)","0","mstr_discrete","I57";
;
PACK_TYPE"0805"
PART_NUMBER"C95333-006"
VOLTAGE"4V"
TOLERANCE"20%"
MATERIAL"X6S"
VALUE"47UF"
LOCATION"C5P40"
GROUP"PWR_MLCC_CAP"
ROOM"PVCCIN_CPU0_DECAP_VR"
CDS_LOCATION"C5P40"
$SEC"1"
CDS_SEC"1"
CDS_LIB"mstr_discrete"
BOM_COST"PROC_SOCKET";
"A"
$PN"1"17;
"B"
$PN"2"37;
%"GND"
"1","(-6550,575)","0","mstr_symbols","I58";
;
HDL_POWER"GND"
BODY_TYPE"PLUMBING"
CDS_LIB"mstr_symbols"
SIZE"1B"
VOLTAGE"0";
"A\NAC"37;
%"PVCCIN_CPU0"
"1","(-7750,2550)","0","mstr_symbols","I62";
;
HDL_POWER"PVCCIN_CPU0"
BODY_TYPE"PLUMBING"
CDS_LIB"mstr_symbols"
VOLTAGE"2.0V";
"G\NAC"38;
%"CAP"
"1","(-7750,2250)","0","mstr_discrete","I63";
;
GROUP"PWR_MLCC_CAP"
PACK_TYPE"0805"
MATERIAL"X6S"
VOLTAGE"4V"
TOLERANCE"20%"
PART_NUMBER"C95333-006"
LOCATION"C5P37"
VALUE"47UF"
ROOM"PVCCIN_CPU0_DECAP_VR"
CDS_LOCATION"C5P37"
$SEC"1"
CDS_SEC"1"
CDS_LIB"mstr_discrete"
BOM_COST"PROC_SOCKET";
"A"
$PN"1"38;
"B"
$PN"2"34;
%"PVCCIN_CPU0"
"1","(-7750,1850)","0","mstr_symbols","I64";
;
VOLTAGE"2.0V"
CDS_LIB"mstr_symbols"
BODY_TYPE"PLUMBING"
HDL_POWER"PVCCIN_CPU0";
"G\NAC"39;
%"CAP"
"1","(-7750,1550)","0","mstr_discrete","I65";
;
GROUP"PWR_MLCC_CAP"
PACK_TYPE"0805"
MATERIAL"X6S"
TOLERANCE"20%"
VOLTAGE"4V"
VALUE"47UF"
LOCATION"C5P36"
PART_NUMBER"C95333-006"
BOM_COST"PROC_SOCKET"
CDS_LIB"mstr_discrete"
CDS_SEC"1"
$SEC"1"
CDS_LOCATION"C5P36"
ROOM"PVCCIN_CPU0_DECAP_VR";
"A"
$PN"1"39;
"B"
$PN"2"35;
%"CAP_A"
"1","(-800,4500)","0","dev_discrete","I68";
;
GROUP"PWR_MCP_CAP"
LOCATION"C6D8"
VALUE"22.0UF"
VOLTAGE"4V"
TOLERANCE"20%"
MATERIAL"X6S"
PART_NUMBER"E15431-004"
PACK_TYPE"0603V"
CDS_LOCATION"C6D8"
BOM_COST"PROC_SOCKET"
CDS_LIB"dev_discrete"
CDS_SEC"1"
$SEC"1"
ROOM"PVCCIN_CPU0_DECAP_VR";
"B"
$PN"2"40;
"A"
$PN"1"13;
%"CAP_A"
"1","(-1050,4500)","0","dev_discrete","I69";
;
PACK_TYPE"0603V"
VALUE"22.0UF"
VOLTAGE"4V"
LOCATION"C5D38"
TOLERANCE"20%"
PART_NUMBER"E15431-004"
MATERIAL"X6S"
GROUP"PWR_MCP_CAP"
ROOM"PVCCIN_CPU0_DECAP_VR"
$SEC"1"
CDS_SEC"1"
CDS_LIB"dev_discrete"
BOM_COST"PROC_SOCKET"
CDS_LOCATION"C5D38";
"B"
$PN"2"40;
"A"
$PN"1"13;
%"CAP_A"
"1","(-1300,4500)","0","dev_discrete","I70";
;
VALUE"22.0UF"
LOCATION"C5D37"
PACK_TYPE"0603V"
VOLTAGE"4V"
PART_NUMBER"E15431-004"
MATERIAL"X6S"
TOLERANCE"20%"
GROUP"PWR_MCP_CAP"
ROOM"PVCCIN_CPU0_DECAP_VR"
$SEC"1"
CDS_SEC"1"
CDS_LIB"dev_discrete"
BOM_COST"PROC_SOCKET"
CDS_LOCATION"C5D37";
"B"
$PN"2"40;
"A"
$PN"1"13;
%"GND"
"1","(-3550,4225)","0","mstr_symbols","I71";
;
HDL_POWER"GND"
BODY_TYPE"PLUMBING"
SIZE"1B"
CDS_LIB"mstr_symbols"
VOLTAGE"0";
"A\NAC"40;
%"CAP_A"
"1","(-3350,3800)","0","dev_discrete","I72";
;
GROUP"PWR_MLCC_CAP"
PART_NUMBER"E15431-004"
PACK_TYPE"0603V"
VOLTAGE"4V"
LOCATION"C6D7"
TOLERANCE"20%"
MATERIAL"X6S"
VALUE"22.0UF"
CDS_LOCATION"C6D7"
BOM_COST"PROC_SOCKET"
CDS_LIB"dev_discrete"
CDS_SEC"1"
$SEC"1"
ROOM"PVCCIN_CPU0_DECAP_VR";
"B"
$PN"2"41;
"A"
$PN"1"42;
%"GND"
"1","(-4100,3525)","0","mstr_symbols","I73";
;
VOLTAGE"0"
CDS_LIB"mstr_symbols"
SIZE"1B"
BODY_TYPE"PLUMBING"
HDL_POWER"GND";
"A\NAC"41;
%"CAP_A"
"1","(-3600,3800)","0","dev_discrete","I74";
;
PART_NUMBER"E15431-004"
PACK_TYPE"0603V"
GROUP"PWR_MLCC_CAP"
TOLERANCE"20%"
VOLTAGE"4V"
MATERIAL"X6S"
VALUE"22.0UF"
LOCATION"C6D4"
ROOM"PVCCIN_CPU0_DECAP_VR"
$SEC"1"
CDS_SEC"1"
CDS_LIB"dev_discrete"
BOM_COST"PROC_SOCKET"
CDS_LOCATION"C6D4";
"B"
$PN"2"41;
"A"
$PN"1"42;
%"CAP_A"
"1","(-1550,4500)","0","dev_discrete","I75";
;
GROUP"PWR_MCP_CAP"
TOLERANCE"20%"
VALUE"22.0UF"
LOCATION"C6D5"
PART_NUMBER"E15431-004"
PACK_TYPE"0603V"
MATERIAL"X6S"
VOLTAGE"4V"
CDS_LOCATION"C6D5"
BOM_COST"PROC_SOCKET"
CDS_LIB"dev_discrete"
CDS_SEC"1"
$SEC"1"
ROOM"PVCCIN_CPU0_DECAP_VR";
"B"
$PN"2"40;
"A"
$PN"1"13;
%"CAP_A"
"1","(-1800,4500)","0","dev_discrete","I77";
;
PACK_TYPE"0603V"
PART_NUMBER"E15431-004"
TOLERANCE"20%"
MATERIAL"X6S"
LOCATION"C6D2"
VALUE"22.0UF"
VOLTAGE"4V"
GROUP"PWR_MCP_CAP"
ROOM"PVCCIN_CPU0_DECAP_VR"
$SEC"1"
CDS_SEC"1"
CDS_LIB"dev_discrete"
BOM_COST"PROC_SOCKET"
CDS_LOCATION"C6D2";
"B"
$PN"2"40;
"A"
$PN"1"13;
%"PVCCIO_CPU0"
"1","(-4100,4100)","0","mstr_symbols","I79";
;
HDL_POWER"PVCCIO_CPU0"
BODY_TYPE"PLUMBING"
CDS_LIB"mstr_symbols"
VOLTAGE"1.1V";
"G\NAC"42;
%"CAP_A"
"1","(-3850,3800)","0","dev_discrete","I80";
;
GROUP"PWR_MLCC_CAP"
VALUE"22.0UF"
VOLTAGE"4V"
TOLERANCE"20%"
LOCATION"C6D3"
MATERIAL"X6S"
PART_NUMBER"E15431-004"
PACK_TYPE"0603V"
ROOM"PVCCIN_CPU0_DECAP_VR"
$SEC"1"
CDS_SEC"1"
CDS_LIB"dev_discrete"
BOM_COST"PROC_SOCKET"
CDS_LOCATION"C6D3";
"B"
$PN"2"41;
"A"
$PN"1"42;
%"CAP_A"
"1","(-4100,3800)","0","dev_discrete","I81";
;
VALUE"22.0UF"
GROUP"PWR_MLCC_CAP"
PART_NUMBER"E15431-004"
MATERIAL"X6S"
VOLTAGE"4V"
TOLERANCE"20%"
PACK_TYPE"0603V"
LOCATION"C6D6"
CDS_LOCATION"C6D6"
BOM_COST"PROC_SOCKET"
CDS_LIB"dev_discrete"
CDS_SEC"1"
$SEC"1"
ROOM"PVCCIN_CPU0_DECAP_VR";
"B"
$PN"2"41;
"A"
$PN"1"42;
%"CAP_A"
"1","(-2550,4500)","0","dev_discrete","I83";
;
VOLTAGE"4V"
VALUE"22.0UF"
MATERIAL"X6S"
LOCATION"C5D51"
TOLERANCE"20%"
PART_NUMBER"E15431-004"
PACK_TYPE"0603V"
GROUP"PWR_MCP_CAP"
CDS_LOCATION"C5D51"
BOM_COST"PROC_SOCKET"
CDS_LIB"dev_discrete"
CDS_SEC"1"
$SEC"1"
ROOM"PVCCIN_CPU0_DECAP_VR";
"B"
$PN"2"40;
"A"
$PN"1"13;
%"CAP_A"
"1","(-2800,4500)","0","dev_discrete","I88";
;
MATERIAL"X6S"
TOLERANCE"20%"
VALUE"22.0UF"
LOCATION"C5D21"
VOLTAGE"4V"
PART_NUMBER"E15431-004"
PACK_TYPE"0603V"
GROUP"PWR_MCP_CAP"
ROOM"PVCCIN_CPU0_DECAP_VR"
$SEC"1"
CDS_SEC"1"
CDS_LIB"dev_discrete"
BOM_COST"PROC_SOCKET"
CDS_LOCATION"C5D21";
"B"
$PN"2"40;
"A"
$PN"1"13;
%"CAP_A"
"1","(-3050,4500)","0","dev_discrete","I89";
;
PART_NUMBER"E15431-004"
MATERIAL"X6S"
TOLERANCE"20%"
LOCATION"C5D50"
VOLTAGE"4V"
PACK_TYPE"0603V"
VALUE"22.0UF"
GROUP"PWR_MCP_CAP"
ROOM"PVCCIN_CPU0_DECAP_VR"
$SEC"1"
CDS_SEC"1"
CDS_LIB"dev_discrete"
BOM_COST"PROC_SOCKET"
CDS_LOCATION"C5D50";
"B"
$PN"2"40;
"A"
$PN"1"13;
%"CAP_A"
"1","(-3300,4500)","0","dev_discrete","I90";
;
LOCATION"C5D48"
VOLTAGE"4V"
VALUE"22.0UF"
TOLERANCE"20%"
MATERIAL"X6S"
PART_NUMBER"E15431-004"
PACK_TYPE"0603V"
GROUP"PWR_MCP_CAP"
ROOM"PVCCIN_CPU0_DECAP_VR"
$SEC"1"
CDS_SEC"1"
CDS_LIB"dev_discrete"
BOM_COST"PROC_SOCKET"
CDS_LOCATION"C5D48";
"B"
$PN"2"40;
"A"
$PN"1"13;
%"CAP"
"1","(-3200,3150)","0","mstr_discrete","I91";
;
PART_NUMBER"E15431-001"
GROUP"PWR_MLCC_CAP"
LOCATION"C5D13"
VALUE"10UF"
MATERIAL"X6S"
TOLERANCE"20%"
VOLTAGE"4V"
PACK_TYPE"0603LF"
CDS_LIB"mstr_discrete"
BOM_COST"PROC_SOCKET"
CDS_SEC"1"
$SEC"1"
CDS_LOCATION"C5D13"
ROOM"PVCCIN_CPU0_DECAP_VR";
"A"
$PN"1"44;
"B"
$PN"2"43;
%"GND"
"1","(-4100,2775)","0","mstr_symbols","I92";
;
VOLTAGE"0"
CDS_LIB"mstr_symbols"
SIZE"1B"
BODY_TYPE"PLUMBING"
HDL_POWER"GND";
"A\NAC"43;
%"CAP"
"1","(-3500,3150)","0","mstr_discrete","I93";
;
GROUP"PWR_MLCC_CAP"
PACK_TYPE"0603LF"
PART_NUMBER"E15431-001"
MATERIAL"X6S"
VOLTAGE"4V"
TOLERANCE"20%"
LOCATION"C5D11"
VALUE"10UF"
ROOM"PVCCIN_CPU0_DECAP_VR"
CDS_LOCATION"C5D11"
$SEC"1"
CDS_SEC"1"
BOM_COST"PROC_SOCKET"
CDS_LIB"mstr_discrete";
"A"
$PN"1"44;
"B"
$PN"2"43;
%"CAP"
"1","(-3800,3150)","0","mstr_discrete","I94";
;
VALUE"10UF"
VOLTAGE"4V"
TOLERANCE"20%"
MATERIAL"X6S"
PART_NUMBER"E15431-001"
PACK_TYPE"0603LF"
GROUP"PWR_MLCC_CAP"
LOCATION"C5D12"
ROOM"PVCCIN_CPU0_DECAP_VR"
CDS_LOCATION"C5D12"
$SEC"1"
CDS_SEC"1"
BOM_COST"PROC_SOCKET"
CDS_LIB"mstr_discrete";
"A"
$PN"1"44;
"B"
$PN"2"43;
%"CAP_A"
"1","(-3550,4500)","0","dev_discrete","I98";
;
MATERIAL"X6S"
TOLERANCE"20%"
LOCATION"C5D23"
VALUE"22.0UF"
VOLTAGE"4V"
PACK_TYPE"0603V"
PART_NUMBER"E15431-004"
GROUP"PWR_MCP_CAP"
ROOM"PVCCIN_CPU0_DECAP_VR"
$SEC"1"
CDS_SEC"1"
CDS_LIB"dev_discrete"
BOM_COST"PROC_SOCKET"
CDS_LOCATION"C5D23";
"B"
$PN"2"40;
"A"
$PN"1"13;
%"PVSA_CPU0"
"1","(-4100,3450)","0","mstr_symbols","I99";
;
HDL_POWER"PVSA_CPU0"
BODY_TYPE"PLUMBING"
CDS_LIB"mstr_symbols"
VOLTAGE"1.1V";
"G\NAC"44;
END.
